# T6G (Grand Teton) — schematic netlist excerpt (pin names and nets, part order shuffled) for the footprints in the layout excerpt that follows; sources: Cadence DE-HDL packaged netlist, KiCad conversion of 04192023_DAF0TMB3IC0_F0TG_MB_C_brd_V02_OCP.brd

C2282  Q_CAP  22UF 4V 20% X6S  pkg C0402  page 72 : A = PVDD11_S3_P1 ; B = GND
PC259_C0P1_2  Q_CAP  2.2UF 10V 10% X6S  pkg C0402  page 211 : A = PVDDCR_CPU0_P1_PVCC ; B = GND

(kicad_pcb
	(version 20260206)
	(generator "pcbnew")
	(generator_version "10.0")
	(general
		(thickness 1.6)
		(legacy_teardrops no)
	)
	(paper "A4")
	(title_block
		(title "04192023_DAF0TMB3IC0_F0TG_MB_C_brd_V02_OCP.brd")
		(comment 1 "Grand Teton / footprints 4230-4231 of 8354")
	)
	(layers
		(0 "F.Cu" signal "TOP")
		(4 "In1.Cu" signal "GND")
		(6 "In2.Cu" signal "IN1")
		(8 "In3.Cu" signal "GND1")
		(10 "In4.Cu" signal "IN2")
		(12 "In5.Cu" signal "GND2")
		(14 "In6.Cu" signal "IN3")
		(16 "In7.Cu" signal "GND3")
		(18 "In8.Cu" signal "VCC")
		(20 "In9.Cu" signal "VCC1")
		(22 "In10.Cu" signal "GND4")
		(24 "In11.Cu" signal "IN4")
		(26 "In12.Cu" signal "GND5")
		(28 "In13.Cu" signal "IN5")
		(30 "In14.Cu" signal "GND6")
		(32 "In15.Cu" signal "IN6")
		(34 "In16.Cu" signal "GND7")
		(2 "B.Cu" signal "BOTTOM")
		(9 "F.Adhes" user "F.Adhesive")
		(11 "B.Adhes" user "B.Adhesive")
		(13 "F.Paste" user "Package Geometry/Pastemask Top")
		(15 "B.Paste" user "Package Geometry/Pastemask Bottom")
		(5 "F.SilkS" user "Ref Des/Silkscreen Top")
		(7 "B.SilkS" user "Ref Des/Silkscreen Bottom")
		(1 "F.Mask" user "Board Geometry/Soldermask Top")
		(3 "B.Mask" user "Board Geometry/Soldermask Bottom")
		(17 "Dwgs.User" user "User.Drawings")
		(19 "Cmts.User" user "User.Comments")
		(21 "Eco1.User" user "User.Eco1")
		(23 "Eco2.User" user "User.Eco2")
		(25 "Edge.Cuts" user "Board Geometry/Outline")
		(27 "Margin" user)
		(31 "F.CrtYd" user "Package Geometry/Place Bound Top")
		(29 "B.CrtYd" user "Package Geometry/Place Bound Bottom")
		(35 "F.Fab" user "Ref Des/Assembly Top")
		(33 "B.Fab" user "Ref Des/Assembly Bottom")
	)
	(footprint ""
		(layer "F.Cu")
		(at 94.36481 -182.677562 90)
		(property "Reference" "PC259_C0P1_2"
			(at 0 0 90)
			(layer "F.SilkS")
			(hide yes)
			(effects
				(font
					(size 1.27 1.27)
				)
			)
		)
		(property "Value" ""
			(at 0 0 90)
			(layer "F.Fab")
			(effects
				(font
					(size 1.27 1.27)
				)
			)
		)
		(duplicate_pad_numbers_are_jumpers no)
		(fp_line
			(start 0.7874 -0.4064)
			(end 0.7874 0.4064)
			(stroke
				(width 0.1524)
				(type default)
			)
			(layer "F.SilkS")
		)
		(fp_line
			(start -0.7874 -0.4064)
			(end 0.7874 -0.4064)
			(stroke
				(width 0.1524)
				(type default)
			)
			(layer "F.SilkS")
		)
		(fp_line
			(start 0.7874 0.4064)
			(end -0.7874 0.4064)
			(stroke
				(width 0.1524)
				(type default)
			)
			(layer "F.SilkS")
		)
		(fp_line
			(start -0.7874 0.4064)
			(end -0.7874 -0.4064)
			(stroke
				(width 0.1524)
				(type default)
			)
			(layer "F.SilkS")
		)
		(fp_line
			(start -0.12065 -0.305054)
			(end -0.12065 -0.2794)
			(stroke
				(width 0.1)
				(type default)
			)
			(layer "F.Fab")
		)
		(fp_line
			(start -0.67945 -0.305054)
			(end -0.12065 -0.305054)
			(stroke
				(width 0.1)
				(type default)
			)
			(layer "F.Fab")
		)
		(fp_line
			(start 0.67945 -0.3048)
			(end 0.67945 0.3048)
			(stroke
				(width 0.1)
				(type default)
			)
			(layer "F.Fab")
		)
		(fp_line
			(start 0.12065 -0.3048)
			(end 0.67945 -0.3048)
			(stroke
				(width 0.1)
				(type default)
			)
			(layer "F.Fab")
		)
		(fp_line
			(start 0.12065 -0.2794)
			(end 0.12065 -0.3048)
			(stroke
				(width 0.1)
				(type default)
			)
			(layer "F.Fab")
		)
		(fp_line
			(start -0.12065 -0.2794)
			(end 0.12065 -0.2794)
			(stroke
				(width 0.1)
				(type default)
			)
			(layer "F.Fab")
		)
		(fp_line
			(start 0.120396 0.2794)
			(end -0.12065 0.2794)
			(stroke
				(width 0.1)
				(type default)
			)
			(layer "F.Fab")
		)
		(fp_line
			(start -0.12065 0.2794)
			(end -0.12065 0.3048)
			(stroke
				(width 0.1)
				(type default)
			)
			(layer "F.Fab")
		)
		(fp_line
			(start 0.67945 0.3048)
			(end 0.120396 0.3048)
			(stroke
				(width 0.1)
				(type default)
			)
			(layer "F.Fab")
		)
		(fp_line
			(start 0.120396 0.3048)
			(end 0.120396 0.2794)
			(stroke
				(width 0.1)
				(type default)
			)
			(layer "F.Fab")
		)
		(fp_line
			(start -0.12065 0.3048)
			(end -0.67945 0.3048)
			(stroke
				(width 0.1)
				(type default)
			)
			(layer "F.Fab")
		)
		(fp_line
			(start -0.67945 0.3048)
			(end -0.67945 -0.305054)
			(stroke
				(width 0.1)
				(type default)
			)
			(layer "F.Fab")
		)
		(pad "1" smd circle
			(at -0.40005 0 90)
			(size 0 0)
			(layers "F.Cu" "F.Mask" "F.Paste")
			(net "PVDDCR_CPU0_P1_PVCC")
		)
		(pad "2" smd circle
			(at 0.40005 0 90)
			(size 0 0)
			(layers "F.Cu" "F.Mask" "F.Paste")
			(net "GND")
		)
	)
	(footprint ""
		(layer "F.Cu")
		(at 113.376964 -261.748016 -90)
		(property "Reference" "C2282"
			(at 0 0 270)
			(layer "F.SilkS")
			(hide yes)
			(effects
				(font
					(size 1.27 1.27)
				)
			)
		)
		(property "Value" ""
			(at 0 0 270)
			(layer "F.Fab")
			(effects
				(font
					(size 1.27 1.27)
				)
			)
		)
		(duplicate_pad_numbers_are_jumpers no)
		(fp_line
			(start -0.7874 0.4064)
			(end -0.7874 -0.4064)
			(stroke
				(width 0.1524)
				(type default)
			)
			(layer "F.SilkS")
		)
		(fp_line
			(start 0.7874 0.4064)
			(end -0.7874 0.4064)
			(stroke
				(width 0.1524)
				(type default)
			)
			(layer "F.SilkS")
		)
		(fp_line
			(start -0.7874 -0.4064)
			(end 0.7874 -0.4064)
			(stroke
				(width 0.1524)
				(type default)
			)
			(layer "F.SilkS")
		)
		(fp_line
			(start 0.7874 -0.4064)
			(end 0.7874 0.4064)
			(stroke
				(width 0.1524)
				(type default)
			)
			(layer "F.SilkS")
		)
		(fp_line
			(start -0.67945 0.3048)
			(end -0.67945 -0.305054)
			(stroke
				(width 0.1)
				(type default)
			)
			(layer "F.Fab")
		)
		(fp_line
			(start -0.12065 0.3048)
			(end -0.67945 0.3048)
			(stroke
				(width 0.1)
				(type default)
			)
			(layer "F.Fab")
		)
		(fp_line
			(start 0.120396 0.3048)
			(end 0.120396 0.2794)
			(stroke
				(width 0.1)
				(type default)
			)
			(layer "F.Fab")
		)
		(fp_line
			(start 0.67945 0.3048)
			(end 0.120396 0.3048)
			(stroke
				(width 0.1)
				(type default)
			)
			(layer "F.Fab")
		)
		(fp_line
			(start -0.12065 0.2794)
			(end -0.12065 0.3048)
			(stroke
				(width 0.1)
				(type default)
			)
			(layer "F.Fab")
		)
		(fp_line
			(start 0.120396 0.2794)
			(end -0.12065 0.2794)
			(stroke
				(width 0.1)
				(type default)
			)
			(layer "F.Fab")
		)
		(fp_line
			(start -0.12065 -0.2794)
			(end 0.12065 -0.2794)
			(stroke
				(width 0.1)
				(type default)
			)
			(layer "F.Fab")
		)
		(fp_line
			(start 0.12065 -0.2794)
			(end 0.12065 -0.3048)
			(stroke
				(width 0.1)
				(type default)
			)
			(layer "F.Fab")
		)
		(fp_line
			(start 0.12065 -0.3048)
			(end 0.67945 -0.3048)
			(stroke
				(width 0.1)
				(type default)
			)
			(layer "F.Fab")
		)
		(fp_line
			(start 0.67945 -0.3048)
			(end 0.67945 0.3048)
			(stroke
				(width 0.1)
				(type default)
			)
			(layer "F.Fab")
		)
		(fp_line
			(start -0.67945 -0.305054)
			(end -0.12065 -0.305054)
			(stroke
				(width 0.1)
				(type default)
			)
			(layer "F.Fab")
		)
		(fp_line
			(start -0.12065 -0.305054)
			(end -0.12065 -0.2794)
			(stroke
				(width 0.1)
				(type default)
			)
			(layer "F.Fab")
		)
		(pad "1" smd circle
			(at -0.40005 0 270)
			(size 0 0)
			(layers "F.Cu" "F.Mask" "F.Paste")
			(net "PVDD11_S3_P1")
		)
		(pad "2" smd circle
			(at 0.40005 0 270)
			(size 0 0)
			(layers "F.Cu" "F.Mask" "F.Paste")
			(net "GND")
		)
	)
)
